FILE_TYPE = CONNECTIVITY;
{Allegro Design Entry HDL 16.6-p007 (v16-6-112F) 10/10/2012}
"PAGE_NUMBER" = 214;
0"NC";
1"GND\g";
2"PVCCIO_CPU1\g";
3"GND\g";
4"GND\g";
5"GND\g";
6"GND\g";
7"GND\g";
8"GND\g";
9"GND\g";
10"GND\g";
11"GND\g";
12"GND\g";
13"GND\g";
14"GND\g";
15"GND\g";
16"GND\g";
17"GND\g";
18"GND\g";
19"VR_FET_SW_P12V_STBY_PVCCIN_CPU0\g";
20"PVCCIO_CPU1\g";
21"GND\g";
22"PVCCIO_CPU1\g";
23"GND\g";
24"GND\g";
25"GND\g";
26"P5V_STBY\g";
27"VR_FET_SW_P12V_STBY_PVCCIN_CPU0\g";
28"VR_PVCCIO_CPU1_PH1_VCIN";
29"TP_PVCCIO_CPU1_GL_1";
30"VR_PVCCIO_CPU1_AIREF1";
31"VR_PVCCIO_CPU1_PH1_SW";
32"VR_PVCCIO_CPU1_PWM1";
33"ISENSE_PVCCIO_CPU1_PH1_IMON";
34"A_TSENSE_PVCCIO_CPU1";
35"TP_PVCCIO_CPU1_GL_0";
36"VR_PVCCIO_CPU1_OCSET";
37"VR_PVCCIO_CPU1_PH1_PHASE";
38"VR_PVCCIO_CPU1_PH1_BOOT";
39"VR_PVCCIO_CPU1_PH1_BOOT_R";
40"VR_PVCCIO_CPU1_PH1_SW_RC";
41"VSENSE_PVCCIO_CPU1_SKT_VSEN";
42"VSENSE_PVCCIO_CPU1_SKT_VRTN";
43"VSENSE_PVCCIO_CPU1_AVSP";
44"VSENSE_PVCCIO_CPU1_AVSN";
%"RES"
"1","(-750,1050)","0","mstr_discrete","I101";
;
CDS_SEC"1"
MATERIAL"CHIP"
PART_NUMBER"G21796-017"
TOLERANCE"1%"
WATTAGE"1/16W"
VALUE"100.0"
PACK_TYPE"0402"
LOCATION"R3D28"
ROOM"PVCCIO_CPU1"
SEC"1"
BOM_COST"PROC_VRD_VCCIO_CPU1"
CDS_LOCATION"R3D28"
SEC_TYPE"0402"
CDS_LIB"mstr_discrete";
"B"
$PN"2"1;
"A"
$PN"1"44;
%"GND"
"1","(-500,825)","0","mstr_symbols","I102";
;
ROOM"PVCCIO_CPU0"
BOM_COST"MEM_VRD_PVCCIO_CPU0"
VOLTAGE"0"
CDS_LIB"mstr_symbols"
SIZE"1B"
BODY_TYPE"PLUMBING"
HDL_POWER"GND";
"A\NAC"1;
%"RES"
"1","(-750,2250)","0","mstr_discrete","I105";
;
CDS_SEC"1"
LOCATION"R3E1"
PART_NUMBER"G21796-017"
WATTAGE"1/16W"
PACK_TYPE"0402"
MATERIAL"CHIP"
TOLERANCE"1%"
VALUE"100.0"
CDS_LOCATION"R3E1"
ROOM"PVCCIO_CPU1"
SEC"1"
SEC_TYPE"0402"
BOM_COST"PROC_VRD_VCCIO_CPU1"
CDS_LIB"mstr_discrete";
"B"
$PN"2"2;
"A"
$PN"1"43;
%"PVCCIO_CPU1"
"1","(-500,2525)","0","mstr_symbols","I107";
;
CDS_LIB"mstr_symbols"
VOLTAGE"1.1V"
BODY_TYPE"PLUMBING"
HDL_POWER"PVCCIO_CPU1";
"G\NAC"2;
%"CAP_A"
"1","(3650,3450)","0","dev_discrete","I108";
;
CDS_SEC"1"
GROUP"PWR_MLCC_CAP"
VALUE"22.0UF"
TOLERANCE"20%"
MATERIAL"X6S"
PART_NUMBER"E15431-004"
PACK_TYPE"0603V"
VOLTAGE"4V"
LOCATION"C3E1"
ROOM"PVCCIO_CPU1"
BOM_COST"PROC_VRD_PVCCIO_CPU1"
REUSE_ID"281"
CDS_LOCATION"C3E1"
CDS_LIB"dev_discrete"
SEC"1"
SEC_TYPE"0603V";
"B"
$PN"2"23;
"A"
$PN"1"22;
%"RES"
"2","(3975,3425)","0","mstr_discrete","I109";
;
CDS_SEC"1"
LOCATION"R7R1"
VALUE"51.1"
TOLERANCE"1.0%"
WATTAGE"1/16W"
MATERIAL"CHIP"
PART_NUMBER"G21796-208"
PACK_TYPE"0402"
CDS_LIB"mstr_discrete"
CDS_LOCATION"R7R1"
SEC"1"
SEC_TYPE"0402";
"A"
$PN"1"22;
"B"
$PN"2"23;
%"IR354XX"
"1","(1075,3925)","0","mstr_discrete","I126";
;
CDS_SEC"1"
NO_XNET_CONNECTION"1"
MATERIAL"IC"
LOCATION"EU4E2"
PART_NUMBER"H73684-001"
CDS_LIB"mstr_discrete"
SEC_TYPE"SM"
SEC"1"
CDS_LOCATION"EU4E2"
PACK_TYPE"SM"
VALUE"IR35412";
"TOUT_FLT"
$PN"36"34;
"NC"
$PN"31"0;
"OCSET"
$PN"37"36;
"IOUT"
$PN"38"33;
"SW"
$PN"10"31;
"BOOST"
$PN"33"39;
"REFIN"
$PN"39"30;
"PWM"
$PN"34"32;
"PHASE"
$PN"32"37;
"VIN<0>"
$PN"25"27;
"VCC"
$PN"3"28;
"VIN<1>"
$PN"30"27;
"EN"
$PN"35"26;
"VDRV"
$PN"4"26;
"VOS"
$PN"1"22;
"LGND"
$PN"2"24;
"PGND<1>"
$PN"7"24;
"PGND<2>"
$PN"40"24;
"PGND<0>"
$PN"5"24;
"GL<0>"
$PN"6"35;
"GL<1>"
$PN"41"29;
%"RES"
"2","(3400,4075)","0","mstr_discrete","I127";
;
CDS_LOCATION"R4E21"
LOCATION"R4E21"
VALUE"68.1K"
TOLERANCE"1%"
WATTAGE"1/16W"
MATERIAL"EMPTY"
PACK_TYPE"0402"
PART_NUMBER"G21796-187"
CDS_LIB"mstr_discrete"
CDS_SEC"1"
$SEC"1";
"A"
$PN"1"36;
"B"
$PN"2"3;
%"GND"
"1","(3400,3875)","0","mstr_symbols","I128";
;
VOLTAGE"0"
CDS_LIB"mstr_symbols"
SIZE"1B"
ROOM"PVSA_CPU1_PWR_VR"
BOM_COST"PROC_VRD_VCCIN_CPU0"
BODY_TYPE"PLUMBING"
HDL_POWER"GND";
"A\NAC"3;
%"SHUNT"
"1","(-1250,1750)","0","mstr_misc","I129";
;
CDS_SEC"1"
CDS_LOCATION"SH3D2"
LOCATION"SH3D2"
PART_NUMBER"N_A"
SEC_TYPE"SH0201"
SEC"1"
CDS_LIB"mstr_misc"
MATERIAL"EMPTY"
PACK_TYPE"SH0201"
PIN_SHORT"A:B";
"A"
$PN"1"41;
"B"
$PN"2"43;
%"SHUNT"
"1","(-1250,1300)","0","mstr_misc","I130";
;
CDS_SEC"1"
CDS_LOCATION"SH3D1"
PART_NUMBER"N_A"
LOCATION"SH3D1"
CDS_LIB"mstr_misc"
SEC_TYPE"SH0201"
SEC"1"
MATERIAL"EMPTY"
PACK_TYPE"SH0201"
PIN_SHORT"A:B";
"A"
$PN"1"42;
"B"
$PN"2"44;
%"GND"
"1","(2200,2850)","0","mstr_symbols","I133";
;
CDS_LIB"mstr_symbols"
ROOM"PVCCIN_CPU0_PWR_VR"
BOM_COST"PROC_VRD_VCCIN_CPU0"
VOLTAGE"0"
SIZE"1B"
BODY_TYPE"PLUMBING"
HDL_POWER"GND";
"A\NAC"4;
%"CAP"
"1","(2275,3950)","0","mstr_discrete","I134";
;
CDS_SEC"1"
CDS_LOCATION"CT61"
VALUE"1000PF"
LOCATION"CT61"
POP"NOPOP"
VOLTAGE"50V"
TOLERANCE"10%"
MATERIAL"X7R"
PART_NUMBER"A36096-046"
PACK_TYPE"0402LF"
ROOM"VDDQ_KLM_PWR_VR"
CDS_LIB"mstr_discrete"
SEC"1"
SEC_TYPE"0402LF";
"A"
$PN"1"34;
"B"
$PN"2"5;
%"GND"
"1","(2275,3750)","0","mstr_symbols","I135";
;
SIZE"1B"
VOLTAGE"0"
ROOM"VDDQ_KLM_PWR_VR"
CDS_LIB"mstr_symbols"
BODY_TYPE"PLUMBING"
HDL_POWER"GND";
"A\NAC"5;
%"GND"
"1","(275,3175)","0","mstr_symbols","I136";
;
CDS_LIB"mstr_symbols"
ROOM"PVCCIN_CPU0_PWR_VR"
BOM_COST"PROC_VRD_VCCIN_CPU0"
SIZE"1B"
VOLTAGE"0"
BODY_TYPE"PLUMBING"
HDL_POWER"GND";
"A\NAC"6;
%"CAP_A"
"1","(275,3425)","0","dev_discrete","I137";
;
CDS_SEC"1"
CDS_LOCATION"CT63"
VALUE"0.1UF"
POP"NOPOP"
LOCATION"CT63"
VOLTAGE"16V"
TOLERANCE"10%"
MATERIAL"X7R"
PART_NUMBER"A36096-030"
PACK_TYPE"0402V"
CDS_LIB"dev_discrete"
ROOM"PVCCIN_CPU0_PWR_VR"
SEC"1"
SEC_TYPE"0402V";
"B"
$PN"2"6;
"A"
$PN"1"30;
%"CAP"
"1","(2200,3450)","0","mstr_discrete","I143";
;
CDS_SEC"1"
CDS_LOCATION"CT62"
POP"NOPOP"
PART_NUMBER"A36096-046"
PACK_TYPE"0402LF"
LOCATION"CT62"
VALUE"1000PF"
VOLTAGE"50V"
TOLERANCE"10%"
MATERIAL"X7R"
SEC_TYPE"0402LF"
SEC"1"
ROOM"VDDQ_KLM_PWR_VR"
CDS_LIB"mstr_discrete";
"A"
$PN"1"31;
"B"
$PN"2"40;
%"RES"
"1","(-675,3700)","0","mstr_discrete","I145";
;
CDS_SEC"1"
CDS_LOCATION"RT41"
LOCATION"RT41"
VALUE"0"
MATERIAL"CHIP"
TOLERANCE"5.0%"
PACK_TYPE"0603"
WATTAGE"1/10W"
PART_NUMBER"G22178-002"
CDS_LIB"mstr_discrete"
BOM_COST"NT_GBE_BASE"
ROOM"NIC_SPRV"
SEC"1"
SEC_TYPE"0603";
"B"
$PN"2"39;
"A"
$PN"1"38;
%"SC22U16V5MX-4-GP"
"1","(250,1200)","0","w_hdl","I148";
;
CDS_SEC"1"
CDS_LOCATION"C4E14"
VALUE"SC22U16V5MX-4-GP"
LOCATION"C4E14"
ATTRIBUTE"22UF"
TOLERANCE"20%"
RATED"16V"
TYPE"X6S"
PACK_SIZE"0805"
CDS_LMAN_SYM_OUTLINE"-50,25,50,-25"
CDS_LIB"w_hdl"
PART_NUMBER"078.22611.0811"
SEC_TYPE"SMD-BCG5"
SEC"1"
PACK_TYPE"SMD-BCG5";
"2"
$PN"2"8;
"1"
$PN"1"19;
%"SC22U16V5MX-4-GP"
"1","(550,1200)","0","w_hdl","I149";
;
CDS_SEC"1"
CDS_LOCATION"C22W13"
VALUE"SC22U16V5MX-4-GP"
LOCATION"C22W13"
ATTRIBUTE"22UF"
TOLERANCE"20%"
RATED"16V"
TYPE"X6S"
PACK_SIZE"0805"
PACK_TYPE"SMD-BCG5"
SEC"1"
SEC_TYPE"SMD-BCG5"
PART_NUMBER"078.22611.0811"
CDS_LIB"w_hdl"
CDS_LMAN_SYM_OUTLINE"-50,25,50,-25";
"2"
$PN"2"7;
"1"
$PN"1"19;
%"GND"
"1","(550,950)","0","mstr_symbols","I150";
;
SIZE"1B"
VOLTAGE"0"
ROOM"PVPP_KLM_VR"
BOM_COST"PVPP_KLM_VR"
CDS_LIB"mstr_symbols"
BODY_TYPE"PLUMBING"
HDL_POWER"GND";
"A\NAC"7;
%"GND"
"1","(250,950)","0","mstr_symbols","I151";
;
SIZE"1B"
VOLTAGE"0"
ROOM"PVPP_KLM_VR"
BOM_COST"PVPP_KLM_VR"
CDS_LIB"mstr_symbols"
BODY_TYPE"PLUMBING"
HDL_POWER"GND";
"A\NAC"8;
%"SC22U16V5MX-4-GP"
"1","(850,1200)","0","w_hdl","I152";
;
CDS_SEC"1"
CDS_LOCATION"C22W14"
VALUE"SC22U16V5MX-4-GP"
LOCATION"C22W14"
ATTRIBUTE"22UF"
TOLERANCE"20%"
RATED"16V"
TYPE"X6S"
PACK_SIZE"0805"
PACK_TYPE"SMD-BCG5"
SEC"1"
SEC_TYPE"SMD-BCG5"
PART_NUMBER"078.22611.0811"
CDS_LIB"w_hdl"
CDS_LMAN_SYM_OUTLINE"-50,25,50,-25";
"2"
$PN"2"9;
"1"
$PN"1"19;
%"GND"
"1","(850,950)","0","mstr_symbols","I153";
;
SIZE"1B"
VOLTAGE"0"
ROOM"PVPP_KLM_VR"
BOM_COST"PVPP_KLM_VR"
CDS_LIB"mstr_symbols"
BODY_TYPE"PLUMBING"
HDL_POWER"GND";
"A\NAC"9;
%"SC22U16V5MX-4-GP"
"1","(1150,1200)","0","w_hdl","I154";
;
CDS_SEC"1"
CDS_LOCATION"C22W15"
LOCATION"C22W15"
VALUE"SC22U16V5MX-4-GP"
ATTRIBUTE"22UF"
TOLERANCE"20%"
RATED"16V"
PACK_SIZE"0805"
TYPE"X6S"
CDS_LMAN_SYM_OUTLINE"-50,25,50,-25"
CDS_LIB"w_hdl"
PART_NUMBER"078.22611.0811"
SEC_TYPE"SMD-BCG5"
SEC"1"
PACK_TYPE"SMD-BCG5";
"2"
$PN"2"10;
"1"
$PN"1"19;
%"GND"
"1","(1150,950)","0","mstr_symbols","I155";
;
SIZE"1B"
VOLTAGE"0"
ROOM"PVPP_KLM_VR"
BOM_COST"PVPP_KLM_VR"
CDS_LIB"mstr_symbols"
BODY_TYPE"PLUMBING"
HDL_POWER"GND";
"A\NAC"10;
%"SC22U16V5MX-4-GP"
"1","(2500,1200)","0","w_hdl","I156";
;
CDS_SEC"1"
CDS_LOCATION"C22W18"
VALUE"SC22U16V5MX-4-GP"
ATTRIBUTE"22UF"
PACK_SIZE"0805"
TYPE"X6S"
RATED"16V"
TOLERANCE"20%"
LOCATION"C22W18"
PACK_TYPE"SMD-BCG5"
SEC"1"
SEC_TYPE"SMD-BCG5"
PART_NUMBER"078.22611.0811"
CDS_LIB"w_hdl"
CDS_LMAN_SYM_OUTLINE"-50,25,50,-25";
"2"
$PN"2"11;
"1"
$PN"1"19;
%"GND"
"1","(2500,950)","0","mstr_symbols","I157";
;
CDS_LIB"mstr_symbols"
BOM_COST"PVPP_KLM_VR"
ROOM"PVPP_KLM_VR"
VOLTAGE"0"
SIZE"1B"
BODY_TYPE"PLUMBING"
HDL_POWER"GND";
"A\NAC"11;
%"SC22U16V5MX-4-GP"
"1","(2200,1200)","0","w_hdl","I158";
;
CDS_SEC"1"
CDS_LOCATION"C22W17"
VALUE"SC22U16V5MX-4-GP"
ATTRIBUTE"22UF"
TOLERANCE"20%"
RATED"16V"
PACK_SIZE"0805"
TYPE"X6S"
LOCATION"C22W17"
CDS_LMAN_SYM_OUTLINE"-50,25,50,-25"
CDS_LIB"w_hdl"
PART_NUMBER"078.22611.0811"
SEC_TYPE"SMD-BCG5"
SEC"1"
PACK_TYPE"SMD-BCG5";
"2"
$PN"2"12;
"1"
$PN"1"19;
%"GND"
"1","(2200,950)","0","mstr_symbols","I159";
;
CDS_LIB"mstr_symbols"
BOM_COST"PVPP_KLM_VR"
ROOM"PVPP_KLM_VR"
VOLTAGE"0"
SIZE"1B"
BODY_TYPE"PLUMBING"
HDL_POWER"GND";
"A\NAC"12;
%"SC22U16V5MX-4-GP"
"1","(1900,1200)","0","w_hdl","I160";
;
CDS_SEC"1"
CDS_LOCATION"C22W16"
VALUE"SC22U16V5MX-4-GP"
PACK_SIZE"0805"
TYPE"X6S"
RATED"16V"
TOLERANCE"20%"
LOCATION"C22W16"
ATTRIBUTE"22UF"
CDS_LMAN_SYM_OUTLINE"-50,25,50,-25"
CDS_LIB"w_hdl"
PART_NUMBER"078.22611.0811"
SEC_TYPE"SMD-BCG5"
SEC"1"
PACK_TYPE"SMD-BCG5";
"2"
$PN"2"13;
"1"
$PN"1"19;
%"SC22U16V5MX-4-GP"
"1","(1600,1200)","0","w_hdl","I161";
;
CDS_SEC"1"
CDS_LOCATION"C4E8"
TYPE"X6S"
ATTRIBUTE"22UF"
RATED"16V"
PACK_SIZE"0805"
LOCATION"C4E8"
TOLERANCE"20%"
VALUE"SC22U16V5MX-4-GP"
CDS_LMAN_SYM_OUTLINE"-50,25,50,-25"
CDS_LIB"w_hdl"
PART_NUMBER"078.22611.0811"
SEC_TYPE"SMD-BCG5"
SEC"1"
PACK_TYPE"SMD-BCG5";
"2"
$PN"2"14;
"1"
$PN"1"19;
%"GND"
"1","(1900,950)","0","mstr_symbols","I162";
;
CDS_LIB"mstr_symbols"
BOM_COST"PVPP_KLM_VR"
ROOM"PVPP_KLM_VR"
VOLTAGE"0"
SIZE"1B"
BODY_TYPE"PLUMBING"
HDL_POWER"GND";
"A\NAC"13;
%"GND"
"1","(1600,950)","0","mstr_symbols","I163";
;
SIZE"1B"
VOLTAGE"0"
ROOM"PVPP_KLM_VR"
BOM_COST"PVPP_KLM_VR"
CDS_LIB"mstr_symbols"
BODY_TYPE"PLUMBING"
HDL_POWER"GND";
"A\NAC"14;
%"SC22U16V5MX-4-GP"
"1","(2950,1200)","0","w_hdl","I164";
;
CDS_SEC"1"
CDS_LOCATION"C4E9"
RATED"16V"
TYPE"X6S"
PACK_SIZE"0805"
ATTRIBUTE"22UF"
TOLERANCE"20%"
VALUE"SC22U16V5MX-4-GP"
LOCATION"C4E9"
PACK_TYPE"SMD-BCG5"
SEC"1"
SEC_TYPE"SMD-BCG5"
PART_NUMBER"078.22611.0811"
CDS_LIB"w_hdl"
CDS_LMAN_SYM_OUTLINE"-50,25,50,-25";
"2"
$PN"2"15;
"1"
$PN"1"19;
%"GND"
"1","(2950,950)","0","mstr_symbols","I165";
;
CDS_LIB"mstr_symbols"
BOM_COST"PVPP_KLM_VR"
ROOM"PVPP_KLM_VR"
VOLTAGE"0"
SIZE"1B"
BODY_TYPE"PLUMBING"
HDL_POWER"GND";
"A\NAC"15;
%"SC22U16V5MX-4-GP"
"1","(3850,1200)","0","w_hdl","I166";
;
CDS_SEC"1"
CDS_LOCATION"C22W21"
PACK_SIZE"0805"
TYPE"X6S"
RATED"16V"
TOLERANCE"20%"
VALUE"SC22U16V5MX-4-GP"
LOCATION"C22W21"
ATTRIBUTE"22UF"
PACK_TYPE"SMD-BCG5"
SEC"1"
SEC_TYPE"SMD-BCG5"
PART_NUMBER"078.22611.0811"
CDS_LIB"w_hdl"
CDS_LMAN_SYM_OUTLINE"-50,25,50,-25";
"2"
$PN"2"16;
"1"
$PN"1"19;
%"GND"
"1","(3850,950)","0","mstr_symbols","I167";
;
CDS_LIB"mstr_symbols"
BOM_COST"PVPP_KLM_VR"
ROOM"PVPP_KLM_VR"
VOLTAGE"0"
SIZE"1B"
BODY_TYPE"PLUMBING"
HDL_POWER"GND";
"A\NAC"16;
%"SC22U16V5MX-4-GP"
"1","(3550,1200)","0","w_hdl","I168";
;
CDS_SEC"1"
CDS_LOCATION"C22W20"
VALUE"SC22U16V5MX-4-GP"
TYPE"X6S"
ATTRIBUTE"22UF"
TOLERANCE"20%"
RATED"16V"
PACK_SIZE"0805"
LOCATION"C22W20"
PACK_TYPE"SMD-BCG5"
SEC"1"
SEC_TYPE"SMD-BCG5"
PART_NUMBER"078.22611.0811"
CDS_LIB"w_hdl"
CDS_LMAN_SYM_OUTLINE"-50,25,50,-25";
"2"
$PN"2"17;
"1"
$PN"1"19;
%"SC22U16V5MX-4-GP"
"1","(3250,1200)","0","w_hdl","I169";
;
CDS_SEC"1"
CDS_LOCATION"C22W19"
PACK_SIZE"0805"
TYPE"X6S"
TOLERANCE"20%"
RATED"16V"
ATTRIBUTE"22UF"
LOCATION"C22W19"
VALUE"SC22U16V5MX-4-GP"
PACK_TYPE"SMD-BCG5"
SEC"1"
SEC_TYPE"SMD-BCG5"
PART_NUMBER"078.22611.0811"
CDS_LIB"w_hdl"
CDS_LMAN_SYM_OUTLINE"-50,25,50,-25";
"2"
$PN"2"18;
"1"
$PN"1"19;
%"GND"
"1","(3550,950)","0","mstr_symbols","I170";
;
SIZE"1B"
VOLTAGE"0"
ROOM"PVPP_KLM_VR"
BOM_COST"PVPP_KLM_VR"
CDS_LIB"mstr_symbols"
BODY_TYPE"PLUMBING"
HDL_POWER"GND";
"A\NAC"17;
%"GND"
"1","(3250,950)","0","mstr_symbols","I171";
;
SIZE"1B"
VOLTAGE"0"
ROOM"PVPP_KLM_VR"
BOM_COST"PVPP_KLM_VR"
CDS_LIB"mstr_symbols"
BODY_TYPE"PLUMBING"
HDL_POWER"GND";
"A\NAC"18;
%"UNIVERSAL_POWER"
"1","(3850,1650)","0","mstr_symbols","I172";
;
HDL_POWER"VR_FET_SW_P12V_STBY_PVCCIN_CPU0"
CDS_LIB"mstr_symbols";
"A"19;
%"RES"
"1","(-1575,4750)","0","mstr_discrete","I173";
;
WATTAGE"1/16W"
VALUE"0.0"
LOCATION"R6R5"
TOLERANCE"5%"
PART_NUMBER"G21497-005"
PACK_TYPE"0402"
MATERIAL"CHIP"
CDS_LOCATION"R6R5"
CDS_SEC"1"
ROOM"CPU0"
SEC"1"
SEC_TYPE"0402"
CDS_LIB"mstr_discrete"
BOM_COST"PROC_SIDEBAND";
"B"
$PN"2"26;
"A"
$PN"1"28;
%"IND-150NH-56-GP"
"1","(3000,3650)","1","w_hdl","I174";
;
CDS_SEC"1"
CDS_LOCATION"L4E2"
TYPE"IRMS=66A@DELTA_T<40C"
LOCATION"L4E2"
VALUE"IND-150NH-56-GP"
ATTRIBUTE"150NH"
RATED"ISAT=75A@25C"
PACK_SIZE"DCR=0.17MOHM"
PART_NUMBER"068.1512N.M001"
CDS_LIB"w_hdl"
CDS_LMAN_SYM_OUTLINE"-75,100,75,-100"
SEC_TYPE"DISCRET-GA1"
SEC"1"
PACK_TYPE"DISCRET-GA1";
"F"
$PN"2"22;
"S"
$PN"1"31;
%"SC1U10V2KX-4-GP"
"1","(-1350,4175)","0","w_hdl","I175";
;
CDS_SEC"1"
CDS_LOCATION"C4E28"
LOCATION"C4E28"
VALUE"SC1U10V2KX-4-GP"
ATTRIBUTE"1UF"
TOLERANCE"10%"
RATED"10V"
PACK_SIZE"0402"
PART_NUMBER"78.10523.8FL"
CDS_LIB"w_hdl"
CDS_LMAN_SYM_OUTLINE"-50,25,50,-25"
SEC_TYPE"SMD-BCG6"
SEC"1"
PACK_TYPE"SMD-BCG6";
"2"
$PN"2"25;
"1"
$PN"1"26;
%"1R3F-GP"
"1","(2200,3100)","0","w_hdl","I176";
;
CDS_SEC"1"
CDS_LOCATION"RT42"
RATED"1/10W"
PACK_SIZE"0603"
LOCATION"RT42"
VALUE"1R3F-GP"
TOLERANCE"1%"
ATTRIBUTE"1 OHM"
POP"NOPOP"
CDS_LMAN_SYM_OUTLINE"-50,75,50,-75"
CDS_LIB"w_hdl"
PART_NUMBER"64.1R005.55L"
SEC_TYPE"RCL_GP"
SEC"1"
PACK_TYPE"RCL_GP";
"2"
$PN"2"4;
"1"
$PN"1"40;
%"CAPP"
"1","(2650,2300)","2","mstr_discrete","I177";
;
CDS_SEC"1"
GROUP"PWR_BULK_CAP"
MATERIAL"ALUM"
PART_NUMBER"699013-049"
PACK_TYPE"3018"
LOCATION"C6R12"
VALUE"470UF"
TOLERANCE"20%"
VOLTAGE"2.5V"
CDS_LIB"mstr_discrete"
SEC_TYPE"3018"
SEC"1"
ROOM"PVCCIO_CPU1"
BOM_COST"PROC_VRD_PVCCIO_CPU1"
CDS_LOCATION"C6R12";
"B"
$PN"2"21;
"A"
$PN"1"20;
%"CAPP"
"1","(3200,2300)","2","mstr_discrete","I178";
;
CDS_SEC"1"
GROUP"PWR_BULK_CAP"
MATERIAL"ALUM"
VOLTAGE"2.5V"
PART_NUMBER"699013-049"
PACK_TYPE"3018"
TOLERANCE"20%"
VALUE"470UF"
LOCATION"C4E7"
CDS_LIB"mstr_discrete"
SEC_TYPE"3018"
SEC"1"
ROOM"PVCCIO_CPU1"
BOM_COST"PROC_VRD_PVCCIO_CPU1"
CDS_LOCATION"C4E7";
"B"
$PN"2"21;
"A"
$PN"1"20;
%"CAPP"
"1","(2100,2300)","2","mstr_discrete","I24";
;
CDS_SEC"1"
MATERIAL"ALUM"
VOLTAGE"2.5V"
PART_NUMBER"699013-049"
LOCATION"C6R5"
PACK_TYPE"3018"
TOLERANCE"20%"
VALUE"470UF"
GROUP"PWR_BULK_CAP"
CDS_LIB"mstr_discrete"
CDS_LOCATION"C6R5"
SEC_TYPE"3018"
SEC"1"
ROOM"PVCCIO_CPU1"
BOM_COST"PROC_VRD_PVCCIO_CPU1";
"B"
$PN"2"21;
"A"
$PN"1"20;
%"PVCCIO_CPU1"
"1","(2100,2600)","0","mstr_symbols","I3";
;
CDS_LIB"mstr_symbols"
VOLTAGE"1.1V"
BODY_TYPE"PLUMBING"
HDL_POWER"PVCCIO_CPU1";
"G\NAC"20;
%"GND"
"1","(2100,1975)","0","mstr_symbols","I6";
;
CDS_LIB"mstr_symbols"
VOLTAGE"0"
SIZE"1B"
ROOM"PVCCIO_CPU1"
BOM_COST"PROC_VRD_PVCCIO_CPU1"
BODY_TYPE"PLUMBING"
HDL_POWER"GND";
"A\NAC"21;
%"PVCCIO_CPU1"
"1","(3975,3725)","0","mstr_symbols","I64";
;
VOLTAGE"1.1V"
CDS_LIB"mstr_symbols"
ROOM"PVCCIO_CPU1"
BOM_COST"PROC_VRD_PVCCIO_CPU1"
BODY_TYPE"PLUMBING"
HDL_POWER"PVCCIO_CPU1";
"G\NAC"22;
%"CAP_A"
"1","(3350,3425)","0","dev_discrete","I65";
;
GROUP"PWR_MLCC_CAP"
PART_NUMBER"E15431-004"
PACK_TYPE"0603V"
MATERIAL"X6S"
TOLERANCE"20%"
VOLTAGE"4V"
VALUE"22.0UF"
LOCATION"C7R1"
CDS_LIB"dev_discrete"
CDS_LOCATION"C7R1"
CDS_SEC"1"
BOM_COST"PROC_VRD_PVCCIO_CPU1"
SEC_TYPE"0603V"
SEC"1"
ROOM"PVCCIO_CPU1";
"B"
$PN"2"23;
"A"
$PN"1"22;
%"GND"
"1","(3975,3150)","0","mstr_symbols","I66";
;
ROOM"PVCCIO_CPU1"
BOM_COST"PROC_VRD_PVCCIO_CPU1"
VOLTAGE"0.0V"
SIZE"1B"
CDS_LIB"mstr_symbols"
BODY_TYPE"PLUMBING"
HDL_POWER"GND";
"A\NAC"23;
%"GND"
"1","(1725,3250)","0","mstr_symbols","I68";
;
ROOM"PVCCIO_CPU1"
BOM_COST"PROC_VRD_PVCCIO_CPU1"
VOLTAGE"0.0V"
CDS_LIB"mstr_symbols"
SIZE"1B"
BODY_TYPE"PLUMBING"
HDL_POWER"GND";
"A\NAC"24;
%"CAP"
"1","(-950,4200)","0","mstr_discrete","I73";
;
CDS_SEC"1"
VALUE"0.22UF"
VOLTAGE"16V"
TOLERANCE"10%"
PACK_TYPE"0402"
PART_NUMBER"A36096-155"
MATERIAL"X7R"
LOCATION"C4E23"
CDS_LIB"mstr_discrete"
CDS_LOCATION"C4E23"
SEC"1"
SEC_TYPE"0402"
ROOM"PVCCIO_CPU1";
"A"
$PN"1"26;
"B"
$PN"2"25;
%"CAP"
"1","(-1700,4150)","0","mstr_discrete","I76";
;
CDS_SEC"1"
PACK_TYPE"0402"
PART_NUMBER"D97712-011"
TOLERANCE"10%"
MATERIAL"X6S"
VOLTAGE"16V"
VALUE"1.0UF"
LOCATION"C4E22"
CDS_LOCATION"C4E22"
CDS_LIB"mstr_discrete"
ROOM"PVCCIO_CPU1"
SEC"1"
SEC_TYPE"0402";
"A"
$PN"1"28;
"B"
$PN"2"25;
%"CAP_A"
"1","(-1975,4150)","0","dev_discrete","I77";
;
TOLERANCE"10%"
MATERIAL"X7R"
PART_NUMBER"A36096-030"
PACK_TYPE"0402V"
VOLTAGE"16V"
VALUE"0.1UF"
LOCATION"C4E13"
ROOM"PVCCIO_CPU1"
SEC"1"
SEC_TYPE"0402V"
CDS_SEC"1"
CDS_LOCATION"C4E13"
CDS_LIB"dev_discrete";
"B"
$PN"2"25;
"A"
$PN"1"27;
%"CAP"
"1","(-1625,3575)","2","mstr_discrete","I78";
;
CDS_SEC"1"
PACK_TYPE"0402"
PART_NUMBER"A36096-104"
MATERIAL"X7R"
TOLERANCE"10%"
VOLTAGE"16V"
VALUE"0.220UF"
LOCATION"C4E18"
CDS_LOCATION"C4E18"
CDS_LIB"mstr_discrete"
SEC_TYPE"0402"
SEC"1"
SPOF"TRUE"
ROOM"PVCCIO_CPU1";
"A"
$PN"1"38;
"B"
$PN"2"37;
%"CAP"
"1","(-2250,4150)","0","mstr_discrete","I79";
;
CDS_SEC"1"
VOLTAGE"16V"
VALUE"1.0UF"
LOCATION"C4E15"
PACK_TYPE"0402"
PART_NUMBER"D97712-011"
MATERIAL"X6S"
TOLERANCE"10%"
CDS_LIB"mstr_discrete"
CDS_LOCATION"C4E15"
SEC"1"
SEC_TYPE"0402"
ROOM"PVCCIO_CPU1";
"A"
$PN"1"27;
"B"
$PN"2"25;
%"CAP"
"1","(-2525,4150)","0","mstr_discrete","I80";
;
CDS_SEC"1"
PACK_TYPE"0805"
MATERIAL"X6S"
VOLTAGE"16V"
TOLERANCE"10%"
VALUE"10UF"
LOCATION"C6R14"
PART_NUMBER"C95333-007"
CDS_LIB"mstr_discrete"
CDS_LOCATION"C6R14"
SEC"1"
SEC_TYPE"0805"
ROOM"PVCCIO_CPU1";
"A"
$PN"1"27;
"B"
$PN"2"25;
%"CAP"
"1","(-2800,4150)","0","mstr_discrete","I81";
;
CDS_SEC"1"
TOLERANCE"10%"
VOLTAGE"16V"
VALUE"10UF"
PACK_TYPE"0805"
LOCATION"C6R10"
PART_NUMBER"C95333-007"
MATERIAL"X6S"
SEC_TYPE"0805"
SEC"1"
ROOM"PVCCIO_CPU1"
CDS_LOCATION"C6R10"
CDS_LIB"mstr_discrete";
"A"
$PN"1"27;
"B"
$PN"2"25;
%"CAP"
"1","(-3100,4150)","0","mstr_discrete","I83";
;
CDS_SEC"1"
LOCATION"C6R8"
VALUE"10UF"
MATERIAL"X6S"
PACK_TYPE"0805"
VOLTAGE"16V"
TOLERANCE"10%"
PART_NUMBER"C95333-007"
ROOM"PVCCIO_CPU1"
SEC"1"
SEC_TYPE"0805"
CDS_LOCATION"C6R8"
CDS_LIB"mstr_discrete";
"A"
$PN"1"27;
"B"
$PN"2"25;
%"GND"
"1","(-3100,3825)","0","mstr_symbols","I84";
;
VOLTAGE"0.0V"
CDS_LIB"mstr_symbols"
SIZE"1B"
ROOM"PVCCIO_CPU1"
BOM_COST"PROC_VRD_PVCCIO_CPU1"
BODY_TYPE"PLUMBING"
HDL_POWER"GND";
"A\NAC"25;
%"P5V_STBY"
"1","(-675,4850)","0","mstr_symbols","I88";
;
VOLTAGE"5.0V"
SIZE"1B"
CDS_LIB"mstr_symbols"
BODY_TYPE"PLUMBING"
HDL_POWER"P5V_STBY";
"G\NAC"26;
%"UNIVERSAL_POWER"
"1","(-3100,4550)","0","mstr_symbols","I89";
;
HDL_POWER"VR_FET_SW_P12V_STBY_PVCCIN_CPU0"
CDS_LIB"mstr_symbols";
"A"27;
%"CAP_A"
"1","(-1725,1575)","0","dev_discrete","I96";
;
CDS_SEC"1"
PART_NUMBER"A36096-030"
MATERIAL"EMPTY"
PACK_TYPE"0402V"
LOCATION"C3D27"
VALUE"0.1UF"
VOLTAGE"16V"
TOLERANCE"10%"
SEC_TYPE"0402V"
SEC"1"
ROOM"PVCCIO_CPU1"
CDS_LOCATION"C3D27"
BOM_COST"PROC_VRD_VCCIO_CPU1"
CDS_LIB"dev_discrete";
"B"
$PN"2"42;
"A"
$PN"1"41;
END.
